# TIMECARD (Time Appliance Project (Time Card)) — schematic netlist excerpt (pin names and nets, part order shuffled) for the footprints in the layout excerpt that follows; sources: Cadence DE-HDL packaged netlist, KiCad conversion of R4006-B0001-02_R01.brd

C178  CAPACITOR  0.1UF 10V 10%  pkg SMC_0402R_H022  page 14 : \1\ = XP1R0V_FPGA ; \2\ = SG
C117  CAPACITOR  4.7UF 6.3V 20%  pkg SMC_0402R_H026  page 14 : \1\ = FPGA_MGTAVTT ; \2\ = SG

(kicad_pcb
	(version 20260206)
	(generator "pcbnew")
	(generator_version "10.0")
	(general
		(thickness 1.6)
		(legacy_teardrops no)
	)
	(paper "A4")
	(title_block
		(title "timecard-production-celestica-r4006 — R4006-B0001-02_R01.brd")
		(comment 1 "Time Appliance Project (Time Card) / footprints 1001-1002 of 1113")
	)
	(layers
		(0 "F.Cu" signal "TOP")
		(4 "In1.Cu" signal "L02_GND1")
		(6 "In2.Cu" signal "L03_SIG1")
		(8 "In3.Cu" signal "L04_GND2")
		(10 "In4.Cu" signal "L05_VCC1")
		(12 "In5.Cu" signal "L06_VCC2")
		(14 "In6.Cu" signal "L07_GND3")
		(16 "In7.Cu" signal "L08_SIG2")
		(18 "In8.Cu" signal "L09_GND4")
		(2 "B.Cu" signal "BOTTOM")
		(9 "F.Adhes" user "F.Adhesive")
		(11 "B.Adhes" user "B.Adhesive")
		(13 "F.Paste" user "Package Geometry/Pastemask Top")
		(15 "B.Paste" user "Package Geometry/Pastemask Bottom")
		(5 "F.SilkS" user "Ref Des/Silkscreen Top")
		(7 "B.SilkS" user "Ref Des/Silkscreen Bottom")
		(1 "F.Mask" user "Board Geometry/Soldermask Top")
		(3 "B.Mask" user "Board Geometry/Soldermask Bottom")
		(17 "Dwgs.User" user "User.Drawings")
		(19 "Cmts.User" user "User.Comments")
		(21 "Eco1.User" user "User.Eco1")
		(23 "Eco2.User" user "User.Eco2")
		(25 "Edge.Cuts" user "Board Geometry/Outline")
		(27 "Margin" user)
		(31 "F.CrtYd" user "Package Geometry/Place Bound Top")
		(29 "B.CrtYd" user "Package Geometry/Place Bound Bottom")
		(35 "F.Fab" user "Ref Des/Assembly Top")
		(33 "B.Fab" user "Ref Des/Assembly Bottom")
	)
	(footprint ""
		(layer "B.Cu")
		(at 136.906 -41.275 90)
		(property "Reference" "C178"
			(at 0.762 1.73863 270)
			(unlocked yes)
			(layer "B.SilkS")
			(effects
				(font
					(size 0.7874 0.5842)
					(thickness 0.1524)
				)
				(justify mirror)
			)
		)
		(property "Value" "VAL*"
			(at -0.0762 2.067306 90)
			(unlocked yes)
			(layer "B.Fab")
			(hide yes)
			(effects
				(font
					(size 0.7874 0.5842)
					(thickness 0.1524)
				)
				(justify mirror)
			)
		)
		(property "Tolerance" "TOL*"
			(at -0.0762 3.032506 90)
			(unlocked yes)
			(layer "Cmts.User")
			(hide yes)
			(effects
				(font
					(size 0.7874 0.5842)
					(thickness 0.1524)
				)
				(justify mirror)
			)
		)
		(property "User Part Number" "PARTNUM*"
			(at -0.1016 4.023106 90)
			(unlocked yes)
			(layer "Cmts.User")
			(hide yes)
			(effects
				(font
					(size 0.7874 0.5842)
					(thickness 0.1524)
				)
				(justify mirror)
			)
		)
		(property "Device Type" "CAPACITOR-G105-0B104-CK,0.1UF,A"
			(at -0.0508 1.127506 90)
			(unlocked yes)
			(layer "B.Fab")
			(hide yes)
			(effects
				(font
					(size 0.7874 0.5842)
					(thickness 0.1524)
				)
				(justify mirror)
			)
		)
		(duplicate_pad_numbers_are_jumpers no)
		(fp_line
			(start 1.143 -0.5588)
			(end 1.143 0.5588)
			(stroke
				(width 0.1)
				(type default)
			)
			(layer "B.SilkS")
		)
		(fp_line
			(start -1.143 -0.5588)
			(end 1.143 -0.5588)
			(stroke
				(width 0.1)
				(type default)
			)
			(layer "B.SilkS")
		)
		(fp_line
			(start 1.143 0.5588)
			(end -1.143 0.5588)
			(stroke
				(width 0.1)
				(type default)
			)
			(layer "B.SilkS")
		)
		(fp_line
			(start -1.143 0.5588)
			(end -1.143 -0.5588)
			(stroke
				(width 0.1)
				(type default)
			)
			(layer "B.SilkS")
		)
		(fp_rect
			(start 1.143 -0.5588)
			(end -1.143 0.5588)
			(stroke
				(width 0)
				(type default)
			)
			(fill no)
			(layer "B.CrtYd")
		)
		(fp_line
			(start 0.508 -0.3048)
			(end 0.508 0.3048)
			(stroke
				(width 0.1)
				(type default)
			)
			(layer "B.Fab")
		)
		(fp_line
			(start -0.508 -0.3048)
			(end 0.508 -0.3048)
			(stroke
				(width 0.1)
				(type default)
			)
			(layer "B.Fab")
		)
		(fp_line
			(start 0.508 0.3048)
			(end -0.508 0.3048)
			(stroke
				(width 0.1)
				(type default)
			)
			(layer "B.Fab")
		)
		(fp_line
			(start -0.508 0.3048)
			(end -0.508 -0.3048)
			(stroke
				(width 0.1)
				(type default)
			)
			(layer "B.Fab")
		)
		(pad "1" smd rect
			(at 0.5334 0 270)
			(size 0.7112 0.6096)
			(layers "B.Cu" "B.Mask" "B.Paste")
			(net "XP1R0V_FPGA")
		)
		(pad "2" smd rect
			(at -0.5334 0 270)
			(size 0.7112 0.6096)
			(layers "B.Cu" "B.Mask" "B.Paste")
			(net "SG")
		)
		(zone
			(layer "B.Cu")
			(hatch none 0.5)
			(connect_pads
				(clearance 0)
			)
			(min_thickness 0.25)
			(keepout
				(tracks allowed)
				(vias not_allowed)
				(pads allowed)
				(copperpour not_allowed)
				(footprints allowed)
			)
			(placement
				(enabled no)
				(sheetname "")
			)
			(fill
				(thermal_gap 0.5)
				(thermal_bridge_width 0.5)
				(island_removal_mode 0)
			)
			(polygon
				(pts
					(xy 136.6012 -41.3512) (xy 136.6012 -41.1988) (xy 137.2108 -41.1988) (xy 137.2108 -41.3512)
				)
			)
		)
	)
	(footprint ""
		(layer "B.Cu")
		(at 100.347018 -38.823138 180)
		(property "Reference" "C117"
			(at 42.562018 -1.008888 0)
			(unlocked yes)
			(layer "B.SilkS")
			(effects
				(font
					(size 0.635 0.4064)
					(thickness 0.1524)
				)
				(justify mirror)
			)
		)
		(property "Value" "VAL*"
			(at 0 3.718306 180)
			(unlocked yes)
			(layer "B.Fab")
			(hide yes)
			(effects
				(font
					(size 0.7874 0.5842)
					(thickness 0.127)
				)
				(justify mirror)
			)
		)
		(property "Tolerance" "TOL*"
			(at 0 4.861306 180)
			(unlocked yes)
			(layer "Cmts.User")
			(hide yes)
			(effects
				(font
					(size 0.7874 0.5842)
					(thickness 0.127)
				)
				(justify mirror)
			)
		)
		(property "User Part Number" "PARTNUM*"
			(at 0 2.575306 180)
			(unlocked yes)
			(layer "Cmts.User")
			(hide yes)
			(effects
				(font
					(size 0.7874 0.5842)
					(thickness 0.127)
				)
				(justify mirror)
			)
		)
		(property "Device Type" "CAPACITOR-G105-0F475-BM,4.7UF,A"
			(at 0 1.432306 180)
			(unlocked yes)
			(layer "B.Fab")
			(hide yes)
			(effects
				(font
					(size 0.7874 0.5842)
					(thickness 0.127)
				)
				(justify mirror)
			)
		)
		(duplicate_pad_numbers_are_jumpers no)
		(fp_line
			(start 0.970026 0.4699)
			(end 0.970026 -0.4699)
			(stroke
				(width 0.1)
				(type default)
			)
			(layer "B.SilkS")
		)
		(fp_line
			(start 0.970026 -0.4699)
			(end -0.970026 -0.4699)
			(stroke
				(width 0.1)
				(type default)
			)
			(layer "B.SilkS")
		)
		(fp_line
			(start -0.970026 0.4699)
			(end 0.970026 0.4699)
			(stroke
				(width 0.1)
				(type default)
			)
			(layer "B.SilkS")
		)
		(fp_line
			(start -0.970026 -0.4699)
			(end -0.970026 0.4699)
			(stroke
				(width 0.1)
				(type default)
			)
			(layer "B.SilkS")
		)
		(fp_poly
			(pts
				(xy 0.970026 0.4699) (xy -0.970026 0.4699) (xy -0.970026 -0.4699) (xy 0.970026 -0.4699)
			)
			(stroke
				(width 0)
				(type default)
			)
			(fill no)
			(layer "B.CrtYd")
		)
		(fp_line
			(start 0.508 0.3048)
			(end 0.508 -0.3048)
			(stroke
				(width 0.1)
				(type default)
			)
			(layer "B.Fab")
		)
		(fp_line
			(start 0.508 -0.3048)
			(end -0.508 -0.3048)
			(stroke
				(width 0.1)
				(type default)
			)
			(layer "B.Fab")
		)
		(fp_line
			(start -0.508 0.3048)
			(end 0.508 0.3048)
			(stroke
				(width 0.1)
				(type default)
			)
			(layer "B.Fab")
		)
		(fp_line
			(start -0.508 -0.3048)
			(end -0.508 0.3048)
			(stroke
				(width 0.1)
				(type default)
			)
			(layer "B.Fab")
		)
		(pad "1" smd circle
			(at 0.500126 0)
			(size 0.635 0.635)
			(layers "B.Cu" "B.Mask" "B.Paste")
			(net "FPGA_MGTAVTT")
		)
		(pad "2" smd circle
			(at -0.500126 0)
			(size 0.635 0.635)
			(layers "B.Cu" "B.Mask" "B.Paste")
			(net "SG")
		)
	)
)
